# T6G (Grand Teton) — schematic netlist excerpt (pin names and nets, part order shuffled) for the footprints in the layout excerpt that follows; sources: Cadence DE-HDL packaged netlist, KiCad conversion of 04192023_DAF0TMB3IC0_F0TG_MB_C_brd_V02_OCP.brd

PR2533  Q_SP_RES4P  0.0003 1% CHIP  pkg R2725_4P  page 266
  \1a\  = P12V_PSU
  \1b\  = P12V_HSC_SENSE2_R3_P
  \2a\  = P12V_MAIN_R
  \2b\  = P12V_HSC_SENSE2_R3_N

R6213  Q_RES  10K 1% CHIP  pkg 0402LF  page 176 : A = P3V3_AUX ; B = USB_CPU0_HUB1_MODE_SEL1
R3462  Q_RES  100K 1% EMPTY  pkg 0402LF  page 129 : A = GPU_NVS_PWR_BRAKE_N_R ; B = GND

(kicad_pcb
	(version 20260206)
	(generator "pcbnew")
	(generator_version "10.0")
	(general
		(thickness 1.6)
		(legacy_teardrops no)
	)
	(paper "A4")
	(title_block
		(title "04192023_DAF0TMB3IC0_F0TG_MB_C_brd_V02_OCP.brd")
		(comment 1 "Grand Teton / footprints 272-274 of 8354")
	)
	(layers
		(0 "F.Cu" signal "TOP")
		(4 "In1.Cu" signal "GND")
		(6 "In2.Cu" signal "IN1")
		(8 "In3.Cu" signal "GND1")
		(10 "In4.Cu" signal "IN2")
		(12 "In5.Cu" signal "GND2")
		(14 "In6.Cu" signal "IN3")
		(16 "In7.Cu" signal "GND3")
		(18 "In8.Cu" signal "VCC")
		(20 "In9.Cu" signal "VCC1")
		(22 "In10.Cu" signal "GND4")
		(24 "In11.Cu" signal "IN4")
		(26 "In12.Cu" signal "GND5")
		(28 "In13.Cu" signal "IN5")
		(30 "In14.Cu" signal "GND6")
		(32 "In15.Cu" signal "IN6")
		(34 "In16.Cu" signal "GND7")
		(2 "B.Cu" signal "BOTTOM")
		(9 "F.Adhes" user "F.Adhesive")
		(11 "B.Adhes" user "B.Adhesive")
		(13 "F.Paste" user "Package Geometry/Pastemask Top")
		(15 "B.Paste" user "Package Geometry/Pastemask Bottom")
		(5 "F.SilkS" user "Ref Des/Silkscreen Top")
		(7 "B.SilkS" user "Ref Des/Silkscreen Bottom")
		(1 "F.Mask" user "Board Geometry/Soldermask Top")
		(3 "B.Mask" user "Board Geometry/Soldermask Bottom")
		(17 "Dwgs.User" user "User.Drawings")
		(19 "Cmts.User" user "User.Comments")
		(21 "Eco1.User" user "User.Eco1")
		(23 "Eco2.User" user "User.Eco2")
		(25 "Edge.Cuts" user "Board Geometry/Outline")
		(27 "Margin" user)
		(31 "F.CrtYd" user "Package Geometry/Place Bound Top")
		(29 "B.CrtYd" user "Package Geometry/Place Bound Bottom")
		(35 "F.Fab" user "Ref Des/Assembly Top")
		(33 "B.Fab" user "Ref Des/Assembly Bottom")
	)
	(footprint ""
		(layer "F.Cu")
		(at 105.537 -419.989 180)
		(property "Reference" "R3462"
			(at 0 0 180)
			(layer "F.SilkS")
			(hide yes)
			(effects
				(font
					(size 1.27 1.27)
				)
			)
		)
		(property "Value" ""
			(at 0 0 180)
			(layer "F.Fab")
			(effects
				(font
					(size 1.27 1.27)
				)
			)
		)
		(duplicate_pad_numbers_are_jumpers no)
		(fp_line
			(start 0.7874 0.4064)
			(end -0.7874 0.4064)
			(stroke
				(width 0.1524)
				(type default)
			)
			(layer "F.SilkS")
		)
		(fp_line
			(start 0.7874 -0.4064)
			(end 0.7874 0.4064)
			(stroke
				(width 0.1524)
				(type default)
			)
			(layer "F.SilkS")
		)
		(fp_line
			(start -0.7874 0.4064)
			(end -0.7874 -0.4064)
			(stroke
				(width 0.1524)
				(type default)
			)
			(layer "F.SilkS")
		)
		(fp_line
			(start -0.7874 -0.4064)
			(end 0.7874 -0.4064)
			(stroke
				(width 0.1524)
				(type default)
			)
			(layer "F.SilkS")
		)
		(fp_line
			(start 0.67945 0.3048)
			(end 0.120396 0.3048)
			(stroke
				(width 0.1)
				(type default)
			)
			(layer "F.Fab")
		)
		(fp_line
			(start 0.67945 -0.3048)
			(end 0.67945 0.3048)
			(stroke
				(width 0.1)
				(type default)
			)
			(layer "F.Fab")
		)
		(fp_line
			(start 0.12065 -0.2794)
			(end 0.12065 -0.3048)
			(stroke
				(width 0.1)
				(type default)
			)
			(layer "F.Fab")
		)
		(fp_line
			(start 0.12065 -0.3048)
			(end 0.67945 -0.3048)
			(stroke
				(width 0.1)
				(type default)
			)
			(layer "F.Fab")
		)
		(fp_line
			(start 0.120396 0.3048)
			(end 0.120396 0.2794)
			(stroke
				(width 0.1)
				(type default)
			)
			(layer "F.Fab")
		)
		(fp_line
			(start 0.120396 0.2794)
			(end -0.12065 0.2794)
			(stroke
				(width 0.1)
				(type default)
			)
			(layer "F.Fab")
		)
		(fp_line
			(start -0.12065 0.3048)
			(end -0.67945 0.3048)
			(stroke
				(width 0.1)
				(type default)
			)
			(layer "F.Fab")
		)
		(fp_line
			(start -0.12065 0.2794)
			(end -0.12065 0.3048)
			(stroke
				(width 0.1)
				(type default)
			)
			(layer "F.Fab")
		)
		(fp_line
			(start -0.12065 -0.2794)
			(end 0.12065 -0.2794)
			(stroke
				(width 0.1)
				(type default)
			)
			(layer "F.Fab")
		)
		(fp_line
			(start -0.12065 -0.305054)
			(end -0.12065 -0.2794)
			(stroke
				(width 0.1)
				(type default)
			)
			(layer "F.Fab")
		)
		(fp_line
			(start -0.67945 0.3048)
			(end -0.67945 -0.305054)
			(stroke
				(width 0.1)
				(type default)
			)
			(layer "F.Fab")
		)
		(fp_line
			(start -0.67945 -0.305054)
			(end -0.12065 -0.305054)
			(stroke
				(width 0.1)
				(type default)
			)
			(layer "F.Fab")
		)
		(pad "1" smd circle
			(at -0.40005 0 180)
			(size 0 0)
			(layers "F.Cu" "F.Mask" "F.Paste")
			(net "GPU_NVS_PWR_BRAKE_N_R")
		)
		(pad "2" smd circle
			(at 0.40005 0 180)
			(size 0 0)
			(layers "F.Cu" "F.Mask" "F.Paste")
			(net "GND")
		)
	)
	(footprint ""
		(layer "F.Cu")
		(at 252.144784 -393.91336 -90)
		(property "Reference" "PR2533"
			(at -4.54406 3.082544 90)
			(unlocked yes)
			(layer "F.SilkS")
			(effects
				(font
					(size 0.7874 0.5842)
					(thickness 0.1524)
				)
				(justify left)
			)
		)
		(property "Value" ""
			(at 0 0 270)
			(layer "F.Fab")
			(effects
				(font
					(size 1.27 1.27)
				)
			)
		)
		(duplicate_pad_numbers_are_jumpers no)
		(fp_line
			(start -3.9878 3.5814)
			(end -3.9878 -3.5814)
			(stroke
				(width 0.1524)
				(type default)
			)
			(layer "F.SilkS")
		)
		(fp_line
			(start 3.9878 3.5814)
			(end -3.9878 3.5814)
			(stroke
				(width 0.1524)
				(type default)
			)
			(layer "F.SilkS")
		)
		(fp_line
			(start -3.9878 -3.5814)
			(end 3.9878 -3.5814)
			(stroke
				(width 0.1524)
				(type default)
			)
			(layer "F.SilkS")
		)
		(fp_line
			(start 3.9878 -3.5814)
			(end 3.9878 3.5814)
			(stroke
				(width 0.1524)
				(type default)
			)
			(layer "F.SilkS")
		)
		(fp_line
			(start -3.5306 3.353054)
			(end -3.5306 -3.353054)
			(stroke
				(width 0.1)
				(type default)
			)
			(layer "F.Fab")
		)
		(fp_line
			(start 3.5306 3.353054)
			(end -3.5306 3.353054)
			(stroke
				(width 0.1)
				(type default)
			)
			(layer "F.Fab")
		)
		(fp_line
			(start -3.5306 -3.353054)
			(end 3.5306 -3.353054)
			(stroke
				(width 0.1)
				(type default)
			)
			(layer "F.Fab")
		)
		(fp_line
			(start 3.5306 -3.353054)
			(end 3.5306 3.353054)
			(stroke
				(width 0.1)
				(type default)
			)
			(layer "F.Fab")
		)
		(pad "1A" smd rect
			(at -2.249932 0 90)
			(size 3.2004 6.858)
			(layers "F.Cu" "F.Mask" "F.Paste")
			(net "P12V_PSU")
		)
		(pad "1B" smd rect
			(at -0.776732 0 270)
			(size 0.254 0.508)
			(layers "F.Cu" "F.Mask" "F.Paste")
			(net "P12V_HSC_SENSE2_R3_P")
		)
		(pad "2A" smd rect
			(at 2.249932 0 90)
			(size 3.2004 6.858)
			(layers "F.Cu" "F.Mask" "F.Paste")
			(net "P12V_MAIN_R")
		)
		(pad "2B" smd rect
			(at 0.776732 0 270)
			(size 0.254 0.508)
			(layers "F.Cu" "F.Mask" "F.Paste")
			(net "P12V_HSC_SENSE2_R3_N")
		)
	)
	(footprint ""
		(layer "F.Cu")
		(at 126.804928 -49.153064)
		(property "Reference" "R6213"
			(at 0 0 0)
			(layer "F.SilkS")
			(hide yes)
			(effects
				(font
					(size 1.27 1.27)
				)
			)
		)
		(property "Value" ""
			(at 0 0 0)
			(layer "F.Fab")
			(effects
				(font
					(size 1.27 1.27)
				)
			)
		)
		(duplicate_pad_numbers_are_jumpers no)
		(fp_line
			(start -0.7874 -0.4064)
			(end 0.7874 -0.4064)
			(stroke
				(width 0.1524)
				(type default)
			)
			(layer "F.SilkS")
		)
		(fp_line
			(start -0.7874 0.4064)
			(end -0.7874 -0.4064)
			(stroke
				(width 0.1524)
				(type default)
			)
			(layer "F.SilkS")
		)
		(fp_line
			(start 0.7874 -0.4064)
			(end 0.7874 0.4064)
			(stroke
				(width 0.1524)
				(type default)
			)
			(layer "F.SilkS")
		)
		(fp_line
			(start 0.7874 0.4064)
			(end -0.7874 0.4064)
			(stroke
				(width 0.1524)
				(type default)
			)
			(layer "F.SilkS")
		)
		(fp_line
			(start -0.67945 -0.305054)
			(end -0.12065 -0.305054)
			(stroke
				(width 0.1)
				(type default)
			)
			(layer "F.Fab")
		)
		(fp_line
			(start -0.67945 0.3048)
			(end -0.67945 -0.305054)
			(stroke
				(width 0.1)
				(type default)
			)
			(layer "F.Fab")
		)
		(fp_line
			(start -0.12065 -0.305054)
			(end -0.12065 -0.2794)
			(stroke
				(width 0.1)
				(type default)
			)
			(layer "F.Fab")
		)
		(fp_line
			(start -0.12065 -0.2794)
			(end 0.12065 -0.2794)
			(stroke
				(width 0.1)
				(type default)
			)
			(layer "F.Fab")
		)
		(fp_line
			(start -0.12065 0.2794)
			(end -0.12065 0.3048)
			(stroke
				(width 0.1)
				(type default)
			)
			(layer "F.Fab")
		)
		(fp_line
			(start -0.12065 0.3048)
			(end -0.67945 0.3048)
			(stroke
				(width 0.1)
				(type default)
			)
			(layer "F.Fab")
		)
		(fp_line
			(start 0.120396 0.2794)
			(end -0.12065 0.2794)
			(stroke
				(width 0.1)
				(type default)
			)
			(layer "F.Fab")
		)
		(fp_line
			(start 0.120396 0.3048)
			(end 0.120396 0.2794)
			(stroke
				(width 0.1)
				(type default)
			)
			(layer "F.Fab")
		)
		(fp_line
			(start 0.12065 -0.3048)
			(end 0.67945 -0.3048)
			(stroke
				(width 0.1)
				(type default)
			)
			(layer "F.Fab")
		)
		(fp_line
			(start 0.12065 -0.2794)
			(end 0.12065 -0.3048)
			(stroke
				(width 0.1)
				(type default)
			)
			(layer "F.Fab")
		)
		(fp_line
			(start 0.67945 -0.3048)
			(end 0.67945 0.3048)
			(stroke
				(width 0.1)
				(type default)
			)
			(layer "F.Fab")
		)
		(fp_line
			(start 0.67945 0.3048)
			(end 0.120396 0.3048)
			(stroke
				(width 0.1)
				(type default)
			)
			(layer "F.Fab")
		)
		(pad "1" smd circle
			(at -0.40005 0)
			(size 0 0)
			(layers "F.Cu" "F.Mask" "F.Paste")
			(net "P3V3_AUX")
		)
		(pad "2" smd circle
			(at 0.40005 0)
			(size 0 0)
			(layers "F.Cu" "F.Mask" "F.Paste")
			(net "USB_CPU0_HUB1_MODE_SEL1")
		)
	)
)
